(kicad_pcb
	(version 20260206)
	(generator "pcbnew")
	(generator_version "10.0")
	(general
		(thickness 1.6)
		(legacy_teardrops no)
	)
	(paper "A4")
	(title_block
		(title "Bryce Canyon_R.DPB_16317-1_OCP.brd")
		(comment 1 "Bryce Canyon / footprints 1855-1859 of 2099")
	)
	(layers
		(0 "F.Cu" signal "TOP")
		(4 "In1.Cu" signal "L2GND")
		(6 "In2.Cu" signal "L3")
		(8 "In3.Cu" signal "L4VCC")
		(10 "In4.Cu" signal "L5VCC")
		(12 "In5.Cu" signal "L6")
		(14 "In6.Cu" signal "L7GND")
		(2 "B.Cu" signal "BOTTOM")
		(9 "F.Adhes" user "F.Adhesive")
		(11 "B.Adhes" user "B.Adhesive")
		(13 "F.Paste" user "Package Geometry/Pastemask Top")
		(15 "B.Paste" user "Package Geometry/Pastemask Bottom")
		(5 "F.SilkS" user "Ref Des/Silkscreen Top")
		(7 "B.SilkS" user "Ref Des/Silkscreen Bottom")
		(1 "F.Mask" user "Board Geometry/Soldermask Top")
		(3 "B.Mask" user "Board Geometry/Soldermask Bottom")
		(17 "Dwgs.User" user "User.Drawings")
		(19 "Cmts.User" user "User.Comments")
		(21 "Eco1.User" user "User.Eco1")
		(23 "Eco2.User" user "User.Eco2")
		(25 "Edge.Cuts" user "Board Geometry/Outline")
		(27 "Margin" user)
		(31 "F.CrtYd" user "Package Geometry/Place Bound Top")
		(29 "B.CrtYd" user "Package Geometry/Place Bound Bottom")
		(35 "F.Fab" user "Ref Des/Assembly Top")
		(33 "B.Fab" user "Ref Des/Assembly Bottom")
	)
	(footprint ""
		(layer "F.Cu")
		(at 280.67 -330.1238 -90)
		(property "Reference" "U11"
			(at 0 0 270)
			(layer "F.SilkS")
			(hide yes)
			(effects
				(font
					(size 1.27 1.27)
				)
			)
		)
		(property "Value" "TSLV07APWR-GP"
			(at -7.112 -6.0579 270)
			(unlocked yes)
			(layer "F.Fab")
			(hide yes)
			(effects
				(font
					(size 1.016 1.016)
					(thickness 0.1524)
				)
			)
		)
		(property "Device Type" "TSOIC14H48"
			(at -7.112 -7.5819 270)
			(unlocked yes)
			(layer "F.Fab")
			(hide yes)
			(effects
				(font
					(size 1.016 1.016)
					(thickness 0.1524)
				)
			)
		)
		(duplicate_pad_numbers_are_jumpers no)
		(fp_line
			(start -2.794 3.8227)
			(end -2.794 1.7018)
			(stroke
				(width 0.508)
				(type default)
			)
			(layer "F.SilkS")
		)
		(fp_line
			(start -2.9718 1.778)
			(end -2.9718 -1.778)
			(stroke
				(width 0.1524)
				(type default)
			)
			(layer "F.SilkS")
		)
		(fp_line
			(start 2.1336 1.778)
			(end -2.9718 1.778)
			(stroke
				(width 0.1524)
				(type default)
			)
			(layer "F.SilkS")
		)
		(fp_line
			(start -2.8956 0.4572)
			(end -2.921 0.4572)
			(stroke
				(width 0.1524)
				(type default)
			)
			(layer "F.SilkS")
		)
		(fp_line
			(start -2.4384 0)
			(end -2.8956 0.4572)
			(stroke
				(width 0.1524)
				(type default)
			)
			(layer "F.SilkS")
		)
		(fp_line
			(start -2.9337 -0.4699)
			(end -2.9083 -0.4699)
			(stroke
				(width 0.1524)
				(type default)
			)
			(layer "F.SilkS")
		)
		(fp_line
			(start -2.9083 -0.4699)
			(end -2.4384 0)
			(stroke
				(width 0.1524)
				(type default)
			)
			(layer "F.SilkS")
		)
		(fp_line
			(start -2.9718 -1.778)
			(end 2.1336 -1.778)
			(stroke
				(width 0.1524)
				(type default)
			)
			(layer "F.SilkS")
		)
		(fp_line
			(start 2.1336 -1.778)
			(end 2.1336 1.778)
			(stroke
				(width 0.1524)
				(type default)
			)
			(layer "F.SilkS")
		)
		(fp_poly
			(pts
				(xy -2.1336 -1.7653) (xy 2.1336 -1.7653) (xy 2.1336 1.778) (xy -2.1336 1.778)
			)
			(stroke
				(width 0)
				(type default)
			)
			(fill yes)
			(layer "F.SilkS")
		)
		(fp_rect
			(start -2.5019 3.2004)
			(end 2.5019 -3.2004)
			(stroke
				(width 0)
				(type default)
			)
			(fill no)
			(layer "F.CrtYd")
		)
		(fp_poly
			(pts
				(xy -3.048 4.0894) (xy -3.048 -2.5781) (xy -2.5019 -2.5781) (xy -2.5019 3.2004) (xy 2.5019 3.2004)
				(xy 2.5019 -3.2004) (xy -2.5019 -3.2004) (xy -2.5019 -2.5908) (xy -3.048 -2.5908) (xy -3.048 -4.0894)
				(xy 3.048 -4.0894) (xy 3.048 4.0894)
			)
			(stroke
				(width 0)
				(type default)
			)
			(fill no)
			(layer "F.CrtYd")
		)
		(fp_rect
			(start -3.048 4.0894)
			(end 3.048 -4.0894)
			(stroke
				(width 0)
				(type default)
			)
			(fill no)
			(layer "F.Fab")
		)
		(pad "1" smd rect
			(at -1.94945 2.8194 270)
			(size 0.3556 1.524)
			(layers "F.Cu" "F.Mask" "F.Paste")
			(net "PWM_OUT_C")
		)
		(pad "2" smd rect
			(at -1.30048 2.8194 270)
			(size 0.3556 1.524)
			(layers "F.Cu" "F.Mask" "F.Paste")
			(net "PWM_OUT_FAN1")
		)
		(pad "3" smd rect
			(at -0.65024 2.8194 270)
			(size 0.3556 1.524)
			(layers "F.Cu" "F.Mask" "F.Paste")
			(net "PWM_OUT_C")
		)
		(pad "4" smd rect
			(at 0 2.8194 270)
			(size 0.3556 1.524)
			(layers "F.Cu" "F.Mask" "F.Paste")
			(net "PWM_OUT_FAN2")
		)
		(pad "5" smd rect
			(at 0.65024 2.8194 270)
			(size 0.3556 1.524)
			(layers "F.Cu" "F.Mask" "F.Paste")
			(net "PWM_OUT_D")
		)
		(pad "6" smd rect
			(at 1.30048 2.8194 270)
			(size 0.3556 1.524)
			(layers "F.Cu" "F.Mask" "F.Paste")
			(net "PWM_OUT_FAN0")
		)
		(pad "7" smd rect
			(at 1.94945 2.8194 270)
			(size 0.3556 1.524)
			(layers "F.Cu" "F.Mask" "F.Paste")
			(net "GND")
		)
		(pad "8" smd rect
			(at 1.94945 -2.8194 270)
			(size 0.3556 1.524)
			(layers "F.Cu" "F.Mask" "F.Paste")
			(net "PWM_OUT_FAN3")
		)
		(pad "9" smd rect
			(at 1.30048 -2.8194 270)
			(size 0.3556 1.524)
			(layers "F.Cu" "F.Mask" "F.Paste")
			(net "PWM_OUT_D")
		)
		(pad "10" smd rect
			(at 0.65024 -2.8194 270)
			(size 0.3556 1.524)
			(layers "F.Cu" "F.Mask" "F.Paste")
			(net "Net_1057")
		)
		(pad "11" smd rect
			(at 0 -2.8194 270)
			(size 0.3556 1.524)
			(layers "F.Cu" "F.Mask" "F.Paste")
			(net "Net_234")
		)
		(pad "12" smd rect
			(at -0.65024 -2.8194 270)
			(size 0.3556 1.524)
			(layers "F.Cu" "F.Mask" "F.Paste")
			(net "Net_1056")
		)
		(pad "13" smd rect
			(at -1.30048 -2.8194 270)
			(size 0.3556 1.524)
			(layers "F.Cu" "F.Mask" "F.Paste")
			(net "Net_235")
		)
		(pad "14" smd rect
			(at -1.94945 -2.8194 270)
			(size 0.3556 1.524)
			(layers "F.Cu" "F.Mask" "F.Paste")
			(net "P3V3_IN")
		)
	)
	(footprint ""
		(layer "F.Cu")
		(at 458.216 -243.586)
		(property "Reference" "R327"
			(at 0 0 0)
			(layer "F.SilkS")
			(hide yes)
			(effects
				(font
					(size 1.27 1.27)
				)
			)
		)
		(property "Value" "4K7R2F-GP"
			(at 0.064008 -3.993896 0)
			(unlocked yes)
			(layer "F.Fab")
			(hide yes)
			(effects
				(font
					(size 1.016 1.016)
					(thickness 0.1524)
				)
			)
		)
		(property "Device Type" "R402H16"
			(at 0.064008 -5.517896 0)
			(unlocked yes)
			(layer "F.Fab")
			(hide yes)
			(effects
				(font
					(size 1.016 1.016)
					(thickness 0.1524)
				)
			)
		)
		(duplicate_pad_numbers_are_jumpers no)
		(fp_line
			(start -0.508 -0.9398)
			(end -0.508 0.9398)
			(stroke
				(width 0.1524)
				(type default)
			)
			(layer "F.SilkS")
		)
		(fp_line
			(start 0.508 -0.9398)
			(end -0.508 -0.9398)
			(stroke
				(width 0.1524)
				(type default)
			)
			(layer "F.SilkS")
		)
		(fp_rect
			(start -0.508 0.9398)
			(end 0.508 -0.9398)
			(stroke
				(width 0)
				(type default)
			)
			(fill no)
			(layer "F.CrtYd")
		)
		(fp_rect
			(start -0.508 0.9398)
			(end 0.508 -0.9398)
			(stroke
				(width 0)
				(type default)
			)
			(fill no)
			(layer "F.Fab")
		)
		(pad "1" smd custom
			(at 0 -0.4445)
			(size 0.1397 0.1397)
			(layers "F.Cu" "F.Mask" "F.Paste")
			(net "SW_PWR_R_HDD10")
			(options
				(clearance outline)
				(anchor circle)
			)
			(primitives
				(gr_poly
					(pts
						(arc
							(start -0.1778 -0.2794)
							(mid -0.249642 -0.249642)
							(end -0.2794 -0.1778)
						)
						(arc
							(start -0.2794 0.1778)
							(mid -0.249642 0.249642)
							(end -0.1778 0.2794)
						)
						(arc
							(start 0.1778 0.2794)
							(mid 0.249642 0.249642)
							(end 0.2794 0.1778)
						)
						(arc
							(start 0.2794 -0.1778)
							(mid 0.249642 -0.249642)
							(end 0.1778 -0.2794)
						)
					)
					(width 0)
					(fill yes)
				)
			)
		)
		(pad "2" smd custom
			(at 0 0.4445)
			(size 0.1397 0.1397)
			(layers "F.Cu" "F.Mask" "F.Paste")
			(net "GND")
			(options
				(clearance outline)
				(anchor circle)
			)
			(primitives
				(gr_poly
					(pts
						(arc
							(start -0.1778 -0.2794)
							(mid -0.249642 -0.249642)
							(end -0.2794 -0.1778)
						)
						(arc
							(start -0.2794 0.1778)
							(mid -0.249642 0.249642)
							(end -0.1778 0.2794)
						)
						(arc
							(start 0.1778 0.2794)
							(mid 0.249642 0.249642)
							(end 0.2794 0.1778)
						)
						(arc
							(start 0.2794 -0.1778)
							(mid 0.249642 -0.249642)
							(end 0.1778 -0.2794)
						)
					)
					(width 0)
					(fill yes)
				)
			)
		)
	)
	(footprint ""
		(layer "F.Cu")
		(at 110.5154 -30.6324)
		(property "Reference" "R698"
			(at 0 0 0)
			(layer "F.SilkS")
			(hide yes)
			(effects
				(font
					(size 1.27 1.27)
				)
			)
		)
		(property "Value" "4K7R2J-2-GP"
			(at 0.064008 -3.993896 0)
			(unlocked yes)
			(layer "F.Fab")
			(hide yes)
			(effects
				(font
					(size 1.016 1.016)
					(thickness 0.1524)
				)
			)
		)
		(property "Device Type" "R402H16"
			(at 0.064008 -5.517896 0)
			(unlocked yes)
			(layer "F.Fab")
			(hide yes)
			(effects
				(font
					(size 1.016 1.016)
					(thickness 0.1524)
				)
			)
		)
		(duplicate_pad_numbers_are_jumpers no)
		(fp_line
			(start -0.508 -0.9398)
			(end -0.508 0.9398)
			(stroke
				(width 0.1524)
				(type default)
			)
			(layer "F.SilkS")
		)
		(fp_line
			(start 0.508 -0.9398)
			(end -0.508 -0.9398)
			(stroke
				(width 0.1524)
				(type default)
			)
			(layer "F.SilkS")
		)
		(fp_rect
			(start -0.508 0.9398)
			(end 0.508 -0.9398)
			(stroke
				(width 0)
				(type default)
			)
			(fill no)
			(layer "F.CrtYd")
		)
		(fp_rect
			(start -0.508 0.9398)
			(end 0.508 -0.9398)
			(stroke
				(width 0)
				(type default)
			)
			(fill no)
			(layer "F.Fab")
		)
		(pad "1" smd custom
			(at 0 -0.4445)
			(size 0.1397 0.1397)
			(layers "F.Cu" "F.Mask" "F.Paste")
			(net "P12V_B")
			(options
				(clearance outline)
				(anchor circle)
			)
			(primitives
				(gr_poly
					(pts
						(arc
							(start -0.1778 -0.2794)
							(mid -0.249642 -0.249642)
							(end -0.2794 -0.1778)
						)
						(arc
							(start -0.2794 0.1778)
							(mid -0.249642 0.249642)
							(end -0.1778 0.2794)
						)
						(arc
							(start 0.1778 0.2794)
							(mid 0.249642 0.249642)
							(end 0.2794 0.1778)
						)
						(arc
							(start 0.2794 -0.1778)
							(mid 0.249642 -0.249642)
							(end 0.1778 -0.2794)
						)
					)
					(width 0)
					(fill yes)
				)
			)
		)
		(pad "2" smd custom
			(at 0 0.4445)
			(size 0.1397 0.1397)
			(layers "F.Cu" "F.Mask" "F.Paste")
			(net "SW_HDD_P27")
			(options
				(clearance outline)
				(anchor circle)
			)
			(primitives
				(gr_poly
					(pts
						(arc
							(start -0.1778 -0.2794)
							(mid -0.249642 -0.249642)
							(end -0.2794 -0.1778)
						)
						(arc
							(start -0.2794 0.1778)
							(mid -0.249642 0.249642)
							(end -0.1778 0.2794)
						)
						(arc
							(start 0.1778 0.2794)
							(mid 0.249642 0.249642)
							(end 0.2794 0.1778)
						)
						(arc
							(start 0.2794 -0.1778)
							(mid 0.249642 -0.249642)
							(end 0.1778 -0.2794)
						)
					)
					(width 0)
					(fill yes)
				)
			)
		)
	)
	(footprint ""
		(layer "F.Cu")
		(at 163.4998 -356.2096)
		(property "Reference" "R1009"
			(at 0 0 0)
			(layer "F.SilkS")
			(hide yes)
			(effects
				(font
					(size 1.27 1.27)
				)
			)
		)
		(property "Value" "D0003R4026F-GP"
			(at -6.737858 -1.79959 0)
			(unlocked yes)
			(layer "F.Fab")
			(hide yes)
			(effects
				(font
					(size 1.016 1.016)
					(thickness 0.1524)
				)
			)
		)
		(property "Device Type" "RL4026-4PH149"
			(at -6.737858 -3.32359 0)
			(unlocked yes)
			(layer "F.Fab")
			(hide yes)
			(effects
				(font
					(size 1.016 1.016)
					(thickness 0.1524)
				)
			)
		)
		(duplicate_pad_numbers_are_jumpers no)
		(fp_line
			(start -5.6769 2.4765)
			(end -5.6769 4.0259)
			(stroke
				(width 0.3302)
				(type default)
			)
			(layer "F.SilkS")
		)
		(fp_line
			(start -5.6769 4.0259)
			(end -4.1402 4.0259)
			(stroke
				(width 0.3302)
				(type default)
			)
			(layer "F.SilkS")
		)
		(fp_line
			(start -5.588 -3.937)
			(end 5.588 -3.937)
			(stroke
				(width 0.1524)
				(type default)
			)
			(layer "F.SilkS")
		)
		(fp_line
			(start -5.588 3.937)
			(end -5.588 -3.937)
			(stroke
				(width 0.1524)
				(type default)
			)
			(layer "F.SilkS")
		)
		(fp_line
			(start 5.588 -3.937)
			(end 5.588 3.937)
			(stroke
				(width 0.1524)
				(type default)
			)
			(layer "F.SilkS")
		)
		(fp_line
			(start 5.588 3.937)
			(end -5.588 3.937)
			(stroke
				(width 0.1524)
				(type default)
			)
			(layer "F.SilkS")
		)
		(fp_poly
			(pts
				(xy -4.703572 3.998468) (xy -5.289804 4.5847) (xy -4.11734 4.5847)
			)
			(stroke
				(width 0)
				(type default)
			)
			(fill yes)
			(layer "F.SilkS")
		)
		(fp_rect
			(start -5.0546 3.302)
			(end 5.0546 -3.302)
			(stroke
				(width 0)
				(type default)
			)
			(fill no)
			(layer "F.CrtYd")
		)
		(fp_poly
			(pts
				(xy -5.842 4.191) (xy -5.842 -4.191) (xy 5.842 -4.191) (xy 5.842 -0.00635) (xy 5.0546 -0.00635)
				(xy 5.0546 -3.302) (xy -5.0546 -3.302) (xy -5.0546 3.302) (xy 5.0546 3.302) (xy 5.0546 0.00635)
				(xy 5.842 0.00635) (xy 5.842 4.191)
			)
			(stroke
				(width 0)
				(type default)
			)
			(fill no)
			(layer "F.CrtYd")
		)
		(fp_rect
			(start -5.842 4.191)
			(end 5.842 -4.191)
			(stroke
				(width 0)
				(type default)
			)
			(fill no)
			(layer "F.Fab")
		)
		(pad "1" smd rect
			(at -4.115054 0.890016)
			(size 2.4384 5.588)
			(layers "F.Cu" "F.Mask" "F.Paste")
			(net "P12V_CLIP")
		)
		(pad "2" smd rect
			(at 4.115054 0.890016)
			(size 2.4384 5.588)
			(layers "F.Cu" "F.Mask" "F.Paste")
			(net "MB0_P12V_IN_R")
		)
		(pad "3" smd rect
			(at -4.115054 -3.245104)
			(size 2.4384 0.889)
			(layers "F.Cu" "F.Mask" "F.Paste")
			(net "MB0_CM_SENSE_R1_P")
		)
		(pad "4" smd rect
			(at 4.115054 -3.245104)
			(size 2.4384 0.889)
			(layers "F.Cu" "F.Mask" "F.Paste")
			(net "MB0_CM_SENSE_R1_N")
		)
		(zone
			(layer "F.Cu")
			(hatch none 0.5)
			(connect_pads
				(clearance 0)
			)
			(min_thickness 0.25)
			(keepout
				(tracks allowed)
				(vias not_allowed)
				(pads allowed)
				(copperpour not_allowed)
				(footprints allowed)
			)
			(placement
				(enabled no)
				(sheetname "")
			)
			(fill
				(thermal_gap 0.5)
				(thermal_bridge_width 0.5)
				(island_removal_mode 0)
			)
			(polygon
				(pts
					(xy 158.165546 -359.010204) (xy 158.165546 -358.113584) (xy 160.603946 -358.113584) (xy 160.603946 -359.010204)
				)
			)
		)
		(zone
			(layer "F.Cu")
			(hatch none 0.5)
			(connect_pads
				(clearance 0)
			)
			(min_thickness 0.25)
			(keepout
				(tracks not_allowed)
				(vias allowed)
				(pads allowed)
				(copperpour not_allowed)
				(footprints allowed)
			)
			(placement
				(enabled no)
				(sheetname "")
			)
			(fill
				(thermal_gap 0.5)
				(thermal_bridge_width 0.5)
				(island_removal_mode 0)
			)
			(polygon
				(pts
					(xy 158.165546 -358.113584) (xy 160.603946 -358.113584) (xy 160.603946 -359.010204) (xy 158.165546 -359.010204)
				)
			)
		)
		(zone
			(layer "F.Cu")
			(hatch none 0.5)
			(connect_pads
				(clearance 0)
			)
			(min_thickness 0.25)
			(keepout
				(tracks allowed)
				(vias not_allowed)
				(pads allowed)
				(copperpour not_allowed)
				(footprints allowed)
			)
			(placement
				(enabled no)
				(sheetname "")
			)
			(fill
				(thermal_gap 0.5)
				(thermal_bridge_width 0.5)
				(island_removal_mode 0)
			)
			(polygon
				(pts
					(xy 166.395654 -359.010204) (xy 166.395654 -358.113584) (xy 168.834054 -358.113584) (xy 168.834054 -359.010204)
				)
			)
		)
		(zone
			(layer "F.Cu")
			(hatch none 0.5)
			(connect_pads
				(clearance 0)
			)
			(min_thickness 0.25)
			(keepout
				(tracks not_allowed)
				(vias allowed)
				(pads allowed)
				(copperpour not_allowed)
				(footprints allowed)
			)
			(placement
				(enabled no)
				(sheetname "")
			)
			(fill
				(thermal_gap 0.5)
				(thermal_bridge_width 0.5)
				(island_removal_mode 0)
			)
			(polygon
				(pts
					(xy 166.395654 -358.113584) (xy 168.834054 -358.113584) (xy 168.834054 -359.010204) (xy 166.395654 -359.010204)
				)
			)
		)
	)
	(footprint ""
		(layer "F.Cu")
		(at 98.806 -151.003 90)
		(property "Reference" "R396"
			(at 0 0 90)
			(layer "F.SilkS")
			(hide yes)
			(effects
				(font
					(size 1.27 1.27)
				)
			)
		)
		(property "Value" "220R3F-1-GP"
			(at -0.0254 -2.5146 90)
			(unlocked yes)
			(layer "F.Fab")
			(hide yes)
			(effects
				(font
					(size 1.016 1.016)
					(thickness 0.1524)
				)
			)
		)
		(property "Device Type" "R603H22"
			(at -0.0254 -4.0386 90)
			(unlocked yes)
			(layer "F.Fab")
			(hide yes)
			(effects
				(font
					(size 1.016 1.016)
					(thickness 0.1524)
				)
			)
		)
		(duplicate_pad_numbers_are_jumpers no)
		(fp_line
			(start 0.2032 0)
			(end 0.4826 0)
			(stroke
				(width 0.2032)
				(type default)
			)
			(layer "F.SilkS")
		)
		(fp_line
			(start -0.4826 0)
			(end -0.2032 0)
			(stroke
				(width 0.2032)
				(type default)
			)
			(layer "F.SilkS")
		)
		(fp_rect
			(start -0.5842 1.3335)
			(end 0.5842 -1.3335)
			(stroke
				(width 0)
				(type default)
			)
			(fill no)
			(layer "F.CrtYd")
		)
		(fp_rect
			(start -0.5842 1.3335)
			(end 0.5842 -1.3335)
			(stroke
				(width 0)
				(type default)
			)
			(fill no)
			(layer "F.Fab")
		)
		(pad "1" smd custom
			(at 0 -0.762 90)
			(size 0.2159 0.2159)
			(layers "F.Cu" "F.Mask" "F.Paste")
			(net "HDD_PRSNT_14")
			(options
				(clearance outline)
				(anchor circle)
			)
			(primitives
				(gr_poly
					(pts
						(arc
							(start -0.3302 -0.4318)
							(mid -0.402042 -0.402042)
							(end -0.4318 -0.3302)
						)
						(arc
							(start -0.4318 0.3302)
							(mid -0.402042 0.402042)
							(end -0.3302 0.4318)
						)
						(arc
							(start 0.3302 0.4318)
							(mid 0.402042 0.402042)
							(end 0.4318 0.3302)
						)
						(arc
							(start 0.4318 -0.3302)
							(mid 0.402042 -0.402042)
							(end 0.3302 -0.4318)
						)
					)
					(width 0)
					(fill yes)
				)
			)
		)
		(pad "2" smd custom
			(at 0 0.762 90)
			(size 0.2159 0.2159)
			(layers "F.Cu" "F.Mask" "F.Paste")
			(net "DRIVE_B_14_INS")
			(options
				(clearance outline)
				(anchor circle)
			)
			(primitives
				(gr_poly
					(pts
						(arc
							(start -0.3302 -0.4318)
							(mid -0.402042 -0.402042)
							(end -0.4318 -0.3302)
						)
						(arc
							(start -0.4318 0.3302)
							(mid -0.402042 0.402042)
							(end -0.3302 0.4318)
						)
						(arc
							(start 0.3302 0.4318)
							(mid 0.402042 0.402042)
							(end 0.4318 0.3302)
						)
						(arc
							(start 0.4318 -0.3302)
							(mid 0.402042 -0.402042)
							(end 0.3302 -0.4318)
						)
					)
					(width 0)
					(fill yes)
				)
			)
		)
	)
)
